# BASEBOARD_FAB2 (Tioga Pass) — schematic parts with pin connectivity, parts 2372–2373 of 4751; source: Cadence DE-HDL packaged netlist (pstxprt.dat, pstxnet.dat, pstchip.dat)

J6E1  SCONN120_H61426002  CONN  pkg SM  page 194
  A1  IOA1  BI  = PVCCMCP_CPU0
  A2  IOA2  BI  = PVCCMCP_CPU0
  A3  IOA3  BI  = PVCCMCP_CPU0
  A4  IOA4  BI  = VSENSE_PVCCMCP_CPU0_SKT_VSEN
  A5  IOA5  BI  = PVCCMCP_CPU0
  A6  IOA6  BI  = PVCCMCP_CPU0
  A7  IOA7  BI  = PVCCMCP_CPU0
  A8  IOA8  BI  = PVCCMCP_CPU0
  A9  IOA9  BI  = PVCCMCP_CPU0
  A10  IOA10  BI  = PVCCMCP_CPU0
  A11  IOA11  BI  = PVCCMCP_CPU0
  A12  IOA12  BI  = PVCCMCP_CPU0
  A13  IOA13  BI  = PVCCMCP_CPU0
  A14  IOA14  BI  = PVCCMCP_CPU0
  A15  IOA15  BI  = PVCCMCP_CPU0
  A16  IOA16  BI  = PVCCMCP_CPU0
  A17  IOA17  BI  = PVCCMCP_CPU0
  A18  IOA18  BI  = PVCCMCP_CPU0
  A19  IOA19  BI  = GND
  A20  IOA20  BI  = GND
  B1  IOB1  BI  = PVCCMCP_CPU0
  B2  IOB2  BI  = PVCCMCP_CPU0
  B3  IOB3  BI  = PVCCMCP_CPU0
  B4  IOB4  BI  = VSENSE_PVCCMCP_CPU0_SKT_VRTN
  B5  IOB5  BI  = PVCCMCP_CPU0
  B6  IOB6  BI  = PVCCMCP_CPU0
  B7  IOB7  BI  = PVCCMCP_CPU0
  B8  IOB8  BI  = PVCCMCP_CPU0
  B9  IOB9  BI  = PVCCMCP_CPU0
  B10  IOB10  BI  = PVCCMCP_CPU0
  B11  IOB11  BI  = PVCCMCP_CPU0
  B12  IOB12  BI  = PVCCMCP_CPU0
  B13  IOB13  BI  = PVCCMCP_CPU0
  B14  IOB14  BI  = PVCCMCP_CPU0
  B15  IOB15  BI  = PVCCMCP_CPU0
  B16  IOB16  BI  = PVCCMCP_CPU0
  B17  IOB17  BI  = PVCCMCP_CPU0
  B18  IOB18  BI  = PVCCMCP_CPU0
  B19  IOB19  BI  = GND
  B20  IOB20  BI  = GND
  C1  IOC1  BI  = PVCCMCP_CPU0
  C2  IOC2  BI  = PVCCMCP_CPU0
  C3  IOC3  BI  = PVCCMCP_CPU0
  C4  IOC4  BI  = PVCCMCP_CPU0
  C5  IOC5  BI  = PVCCMCP_CPU0
  C6  IOC6  BI  = PVCCMCP_CPU0
  C7  IOC7  BI  = PVCCMCP_CPU0
  C8  IOC8  BI  = PVCCMCP_CPU0
  C9  IOC9  BI  = PVCCMCP_CPU0
  C10  IOC10  BI  = PVCCMCP_CPU0
  C11  IOC11  BI  = PVCCMCP_CPU0
  C12  IOC12  BI  = PVCCMCP_CPU0
  C13  IOC13  BI  = PVCCMCP_CPU0
  C14  IOC14  BI  = PVCCMCP_CPU0
  C15  IOC15  BI  = PVCCMCP_CPU0
  C16  IOC16  BI  = PVCCMCP_CPU0
  C17  IOC17  BI  = PVCCMCP_CPU0
  C18  IOC18  BI  = PVCCMCP_CPU0
  C19  IOC19  BI  = GND
  C20  IOC20  BI  = GND
  D1  IOD1  BI  = VSENSE_P1V8MCP_CPU0_SKT_VSEN
  D2  IOD2  BI  = VSENSE_P1V8MCP_CPU0_SKT_VRTN
  D3  IOD3  BI  = P1V8_MCP_CPU0
  D4  IOD4  BI  = GND
  D5  IOD5  BI  = GND
  D6  IOD6  BI  = GND
  D7  IOD7  BI  = GND
  D8  IOD8  BI  = GND
  D9  IOD9  BI  = GND
  D10  IOD10  BI  = GND
  D11  IOD11  BI  = GND
  D12  IOD12  BI  = GND
  D13  IOD13  BI  = GND
  D14  IOD14  BI  = GND
  D15  IOD15  BI  = GND
  D16  IOD16  BI  = GND
  D17  IOD17  BI  = GND
  D18  IOD18  BI  = GND
  D19  IOD19  BI  = GND
  D20  IOD20  BI  = GND
  E1  IOE1  BI  = P1V8_MCP_CPU0
  E2  IOE2  BI  = P1V8_MCP_CPU0
  E3  IOE3  BI  = P1V8_MCP_CPU0
  E4  IOE4  BI  = GND
  E5  IOE5  BI  = CLK_322M_156M_CPU0_OSC_VRM_DP
  E6  IOE6  BI  = GND
  E7  IOE7  BI  = GND
  E8  IOE8  BI  = GND
  E9  IOE9  BI  = GND
  E10  IOE10  BI  = GND
  E11  IOE11  BI  = GND
  E12  IOE12  BI  = GND
  E13  IOE13  BI  = GND
  E14  IOE14  BI  = GND
  E15  IOE15  BI  = GND
  E16  IOE16  BI  = GND
  E17  IOE17  BI  = GND
  E18  IOE18  BI  = GND
  E19  IOE19  BI  = GND
  E20  IOE20  BI  = GND
  F1  IOF1  BI  = P1V8_MCP_CPU0
  F2  IOF2  BI  = P1V8_MCP_CPU0
  F3  IOF3  BI  = P1V8_MCP_CPU0
  F4  IOF4  BI  = GND
  F5  IOF5  BI  = CLK_322M_156M_CPU0_OSC_VRM_DN
  F6  IOF6  BI  = GND
  F7  IOF7  BI  = GND
  F8  IOF8  BI  = GND
  F9  IOF9  BI  = GND
  F10  IOF10  BI  = GND
  F11  IOF11  BI  = GND
  F12  IOF12  BI  = GND
  F13  IOF13  BI  = GND
  F14  IOF14  BI  = GND
  F15  IOF15  BI  = GND
  F16  IOF16  BI  = GND
  F17  IOF17  BI  = GND
  F18  IOF18  BI  = GND
  F19  IOF19  BI  = GND
  F20  IOF20  BI  = GND

J6L1  SCONN288_H44441003  SCONN  pkg PIP  page 54
  1  \12v\(1)  = P12V_NVDIMM_DEF
  2  VSS(93)  GROUND  = GND
  3  DQ(4)  BI  = M_F_DQ<4>
  4  VSS(92)  GROUND  = GND
  5  DQ(0)  BI  = M_F_DQ<0>
  6  VSS(91)  GROUND  = GND
  7  DQS9P  BI  = M_F_DQS_DP<9>
  8  DQS9N  BI  = M_F_DQS_DN<9>
  9  VSS(90)  GROUND  = GND
  10  DQ(6)  BI  = M_F_DQ<6>
  11  VSS(89)  GROUND  = GND
  12  DQ(2)  BI  = M_F_DQ<2>
  13  VSS(88)  GROUND  = GND
  14  DQ(12)  BI  = M_F_DQ<12>
  15  VSS(87)  GROUND  = GND
  16  DQ(8)  BI  = M_F_DQ<8>
  17  VSS(86)  GROUND  = GND
  18  DQS10P  BI  = M_F_DQS_DP<10>
  19  DQS10N  BI  = M_F_DQS_DN<10>
  20  VSS(85)  GROUND  = GND
  21  DQ(14)  BI  = M_F_DQ<14>
  22  VSS(84)  GROUND  = GND
  23  DQ(10)  BI  = M_F_DQ<10>
  24  VSS(83)  GROUND  = GND
  25  DQ(20)  BI  = M_F_DQ<20>
  26  VSS(82)  GROUND  = GND
  27  DQ(16)  BI  = M_F_DQ<16>
  28  VSS(81)  GROUND  = GND
  29  DQS11P  BI  = M_F_DQS_DP<11>
  30  DQS11N  BI  = M_F_DQS_DN<11>
  31  VSS(80)  GROUND  = GND
  32  DQ(22)  BI  = M_F_DQ<22>
  33  VSS(79)  GROUND  = GND
  34  DQ(18)  BI  = M_F_DQ<18>
  35  VSS(78)  GROUND  = GND
  36  DQ(28)  BI  = M_F_DQ<28>
  37  VSS(77)  GROUND  = GND
  38  DQ(24)  BI  = M_F_DQ<24>
  39  VSS(76)  GROUND  = GND
  40  DQS12P  BI  = M_F_DQS_DP<12>
  41  DQS12N  BI  = M_F_DQS_DN<12>
  42  VSS(75)  GROUND  = GND
  43  DQ(30)  BI  = M_F_DQ<30>
  44  VSS(74)  GROUND  = GND
  45  DQ(26)  BI  = M_F_DQ<26>
  46  VSS(73)  GROUND  = GND
  47  CB(4)  BI  = M_F_ECC<4>
  48  VSS(72)  GROUND  = GND
  49  CB(0)  BI  = M_F_ECC<0>
  50  VSS(71)  GROUND  = GND
  51  DQS17P  BI  = M_F_DQS_DP<17>
  52  DQS17N  BI  = M_F_DQS_DN<17>
  53  VSS(70)  GROUND  = GND
  54  CB(6)  BI  = M_F_ECC<6>
  55  VSS(69)  GROUND  = GND
  56  CB(2)  BI  = M_F_ECC<2>
  57  VSS(68)  GROUND  = GND
  58  RESET_N  BI  = M_DEF_RST_N
  59  VDD(25)  POWER  = PVDDQ_DEF
  60  CKE(0)  BI  = M_F_CKE<2>
  61  VDD(24)  POWER  = PVDDQ_DEF
  62  ACT_N  BI  = M_F_ACT_N
  63  BG(0)  BI  = M_F_BG<0>
  64  VDD(23)  POWER  = PVDDQ_DEF
  65  A12  BI  = M_F_MA<12>
  66  A9  BI  = M_F_MA<9>
  67  VDD(22)  POWER  = PVDDQ_DEF
  68  A8  BI  = M_F_MA<8>
  69  A6  BI  = M_F_MA<6>
  70  VDD(21)  POWER  = PVDDQ_DEF
  71  A3  BI  = M_F_MA<3>
  72  A1  BI  = M_F_MA<1>
  73  VDD(20)  POWER  = PVDDQ_DEF
  74  CK0P  BI  = M_F_CLK_DP<2>
  75  CK0N  BI  = M_F_CLK_DN<2>
  76  VDD(19)  POWER  = PVDDQ_DEF
  77  VTT(1)  POWER  = PVTT_DEF
  78  EVENT_N  BI  = FM_DIMM_EVENT_COD_N
  79  A0  BI  = M_F_MA<0>
  80  VDD(18)  POWER  = PVDDQ_DEF
  81  BA(0)  BI  = M_F_BA<0>
  82  A16_RAS_N  BI  = M_F_MA<16>
  83  VDD(17)  POWER  = PVDDQ_DEF
  84  S0_N  BI  = M_F_CS_N<4>
  85  VDD(16)  POWER  = PVDDQ_DEF
  86  A15_CAS_N  BI  = M_F_MA<15>
  87  ODT(0)  BI  = M_F_ODT<2>
  88  VDD(15)  POWER  = PVDDQ_DEF
  89  S1_N  BI  = M_F_CS_N<5>
  90  VDD(14)  POWER  = PVDDQ_DEF
  91  ODT(1)  BI  = M_F_ODT<3>
  92  VDD(13)  POWER  = PVDDQ_DEF
  93  S2_N_C(0)  BI  = M_F_CS_N<6>
  94  VSS(67)  GROUND  = GND
  95  DQ(36)  BI  = M_F_DQ<36>
  96  VSS(66)  GROUND  = GND
  97  DQ(32)  BI  = M_F_DQ<32>
  98  VSS(65)  GROUND  = GND
  99  DQS13P  BI  = M_F_DQS_DP<13>
  100  DQS13N  BI  = M_F_DQS_DN<13>
  101  VSS(64)  GROUND  = GND
  102  DQ(38)  BI  = M_F_DQ<38>
  103  VSS(63)  GROUND  = GND
  104  DQ(34)  BI  = M_F_DQ<34>
  105  VSS(62)  GROUND  = GND
  106  DQ(44)  BI  = M_F_DQ<44>
  107  VSS(61)  GROUND  = GND
  108  DQ(40)  BI  = M_F_DQ<40>
  109  VSS(60)  GROUND  = GND
  110  DQS14P  BI  = M_F_DQS_DP<14>
  111  DQS14N  BI  = M_F_DQS_DN<14>
  112  VSS(59)  GROUND  = GND
  113  DQ(46)  BI  = M_F_DQ<46>
  114  VSS(58)  GROUND  = GND
  115  DQ(42)  BI  = M_F_DQ<42>
  116  VSS(57)  GROUND  = GND
  117  DQ(52)  BI  = M_F_DQ<52>
  118  VSS(56)  GROUND  = GND
  119  DQ(48)  BI  = M_F_DQ<48>
  120  VSS(55)  GROUND  = GND
  121  DQS15P  BI  = M_F_DQS_DP<15>
  122  DQS15N  BI  = M_F_DQS_DN<15>
  123  VSS(54)  GROUND  = GND
  124  DQ(54)  BI  = M_F_DQ<54>
  125  VSS(53)  GROUND  = GND
  126  DQ(50)  BI  = M_F_DQ<50>
  127  VSS(52)  GROUND  = GND
  128  DQ(60)  BI  = M_F_DQ<60>
  129  VSS(51)  GROUND  = GND
  130  DQ(56)  BI  = M_F_DQ<56>
  131  VSS(50)  GROUND  = GND
  132  DQS16P  BI  = M_F_DQS_DP<16>
  133  DQS16N  BI  = M_F_DQS_DN<16>
  134  VSS(49)  GROUND  = GND
  135  DQ(62)  BI  = M_F_DQ<62>
  136  VSS(48)  GROUND  = GND
  137  DQ(58)  BI  = M_F_DQ<58>
  138  VSS(47)  GROUND  = GND
  139  SA(0)  BI  = PVPP_DEF
  140  SA(1)  BI  = GND
  141  SCL  BI  = SMB_DDR_DEF_VPP_SCL
  142  VPP(4)  POWER  = PVPP_DEF
  143  VPP(3)  POWER  = PVPP_DEF
  144  RFU(2)  BI  = TP_CH_F_DIMM_F1_RFU_2
  145  \12v\(0)  = P12V_NVDIMM_DEF
  146  VREFCA  BI  = M_F_VREF
  147  VSS(46)  GROUND  = GND
  148  DQ(5)  BI  = M_F_DQ<5>
  149  VSS(45)  GROUND  = GND
  150  DQ(1)  BI  = M_F_DQ<1>
  151  VSS(44)  GROUND  = GND
  152  DQS0N  BI  = M_F_DQS_DN<0>
  153  DQS0P  BI  = M_F_DQS_DP<0>
  154  VSS(43)  GROUND  = GND
  155  DQ(7)  BI  = M_F_DQ<7>
  156  VSS(42)  GROUND  = GND
  157  DQ(3)  BI  = M_F_DQ<3>
  158  VSS(41)  GROUND  = GND
  159  DQ(13)  BI  = M_F_DQ<13>
  160  VSS(40)  GROUND  = GND
  161  DQ(9)  BI  = M_F_DQ<9>
  162  VSS(39)  GROUND  = GND
  163  DQS1N  BI  = M_F_DQS_DN<1>
  164  DQS1P  BI  = M_F_DQS_DP<1>
  165  VSS(38)  GROUND  = GND
  166  DQ(15)  BI  = M_F_DQ<15>
  167  VSS(37)  GROUND  = GND
  168  DQ(11)  BI  = M_F_DQ<11>
  169  VSS(36)  GROUND  = GND
  170  DQ(21)  BI  = M_F_DQ<21>
  171  VSS(35)  GROUND  = GND
  172  DQ(17)  BI  = M_F_DQ<17>
  173  VSS(34)  GROUND  = GND
  174  DQS2N  BI  = M_F_DQS_DN<2>
  175  DQS2P  BI  = M_F_DQS_DP<2>
  176  VSS(33)  GROUND  = GND
  177  DQ(23)  BI  = M_F_DQ<23>
  178  VSS(32)  GROUND  = GND
  179  DQ(19)  BI  = M_F_DQ<19>
  180  VSS(31)  GROUND  = GND
  181  DQ(29)  BI  = M_F_DQ<29>
  182  VSS(30)  GROUND  = GND
  183  DQ(25)  BI  = M_F_DQ<25>
  184  VSS(29)  GROUND  = GND
  185  DQS3N  BI  = M_F_DQS_DN<3>
  186  DQS3P  BI  = M_F_DQS_DP<3>
  187  VSS(28)  GROUND  = GND
  188  DQ(31)  BI  = M_F_DQ<31>
  189  VSS(27)  GROUND  = GND
  190  DQ(27)  BI  = M_F_DQ<27>
  191  VSS(26)  GROUND  = GND
  192  CB(5)  BI  = M_F_ECC<5>
  193  VSS(25)  GROUND  = GND
  194  CB(1)  BI  = M_F_ECC<1>
  195  VSS(24)  GROUND  = GND
  196  DQS8N  BI  = M_F_DQS_DN<8>
  197  DQS8P  BI  = M_F_DQS_DP<8>
  198  VSS(23)  GROUND  = GND
  199  CB(7)  BI  = M_F_ECC<7>
  200  VSS(22)  GROUND  = GND
  201  CB(3)  BI  = M_F_ECC<3>
  202  VSS(21)  GROUND  = GND
  203  CKE(1)  BI  = M_F_CKE<3>
  204  VDD(12)  POWER  = PVDDQ_DEF
  205  RFU(0)  BI  = TP_CH_F_DIMM_F1_RFU_0
  206  VDD(11)  POWER  = PVDDQ_DEF
  207  BG(1)  BI  = M_F_BG<1>
  208  ALERT_N  BI  = M_F_ALERT_N
  209  VDD(10)  POWER  = PVDDQ_DEF
  210  A11  BI  = M_F_MA<11>
  211  A7  BI  = M_F_MA<7>
  212  VDD(9)  POWER  = PVDDQ_DEF
  213  A5  BI  = M_F_MA<5>
  214  A4  BI  = M_F_MA<4>
  215  VDD(8)  POWER  = PVDDQ_DEF
  216  A2  BI  = M_F_MA<2>
  217  VDD(7)  POWER  = PVDDQ_DEF
  218  CK1P  BI  = M_F_CLK_DP<3>
  219  CK1N  BI  = M_F_CLK_DN<3>
  220  VDD(6)  POWER  = PVDDQ_DEF
  221  VTT(0)  POWER  = PVTT_DEF
  222  PAR  BI  = M_F_PAR
  223  VDD(5)  POWER  = PVDDQ_DEF
  224  BA(1)  BI  = M_F_BA<1>
  225  A10  BI  = M_F_MA<10>
  226  VDD(4)  POWER  = PVDDQ_DEF
  227  RFU(1)  BI  = TP_CH_F_DIMM_F1_RFU_1
  228  A14_WE_N  BI  = M_F_MA<14>
  229  VDD(3)  POWER  = PVDDQ_DEF
  230  SAVE_N_NC  BI  = FM_ADR_COMPLETE_DEF_N
  231  VDD(2)  POWER  = PVDDQ_DEF
  232  A13  BI  = M_F_MA<13>
  233  VDD(1)  POWER  = PVDDQ_DEF
  234  A17  BI  = M_F_MA<17>
  235  C(2)  BI  = M_F_C<2>
  236  VDD(0)  POWER  = PVDDQ_DEF
  237  S3_N_C(1)  BI  = M_F_CS_N<7>
  238  SA(2)  BI  = PVPP_DEF
  239  VSS(20)  GROUND  = GND
  240  DQ(37)  BI  = M_F_DQ<37>
  241  VSS(19)  GROUND  = GND
  242  DQ(33)  BI  = M_F_DQ<33>
  243  VSS(18)  GROUND  = GND
  244  DQS4N  BI  = M_F_DQS_DN<4>
  245  DQS4P  BI  = M_F_DQS_DP<4>
  246  VSS(17)  GROUND  = GND
  247  DQ(39)  BI  = M_F_DQ<39>
  248  VSS(16)  GROUND  = GND
  249  DQ(35)  BI  = M_F_DQ<35>
  250  VSS(15)  GROUND  = GND
  251  DQ(45)  BI  = M_F_DQ<45>
  252  VSS(14)  GROUND  = GND
  253  DQ(41)  BI  = M_F_DQ<41>
  254  VSS(13)  GROUND  = GND
  255  DQS5N  BI  = M_F_DQS_DN<5>
  256  DQS5P  BI  = M_F_DQS_DP<5>
  257  VSS(12)  GROUND  = GND
  258  DQ(47)  BI  = M_F_DQ<47>
  259  VSS(11)  GROUND  = GND
  260  DQ(43)  BI  = M_F_DQ<43>
  261  VSS(10)  GROUND  = GND
  262  DQ(53)  BI  = M_F_DQ<53>
  263  VSS(9)  GROUND  = GND
  264  DQ(49)  BI  = M_F_DQ<49>
  265  VSS(8)  GROUND  = GND
  266  DQS6N  BI  = M_F_DQS_DN<6>
  267  DQS6P  BI  = M_F_DQS_DP<6>
  268  VSS(7)  GROUND  = GND
  269  DQ(55)  BI  = M_F_DQ<55>
  270  VSS(6)  GROUND  = GND
  271  DQ(51)  BI  = M_F_DQ<51>
  272  VSS(5)  GROUND  = GND
  273  DQ(61)  BI  = M_F_DQ<61>
  274  VSS(4)  GROUND  = GND
  275  DQ(57)  BI  = M_F_DQ<57>
  276  VSS(3)  GROUND  = GND
  277  DQS7N  BI  = M_F_DQS_DN<7>
  278  DQS7P  BI  = M_F_DQS_DP<7>
  279  VSS(2)  GROUND  = GND
  280  DQ(63)  BI  = M_F_DQ<63>
  281  VSS(1)  GROUND  = GND
  282  DQ(59)  BI  = M_F_DQ<59>
  283  VSS(0)  GROUND  = GND
  284  VDDSPD  BI  = PVPP_DEF
  285  SDA  BI  = SMB_DDR_DEF_VPP_SDA
  286  VPP(1)  POWER  = PVPP_DEF
  287  VPP(0)  POWER  = PVPP_DEF
  288  VPP(2)  POWER  = PVPP_DEF
